(kicad_pcb
	(version 20241229)
	(generator "pcbnew")
	(generator_version "9.0")
	(general
		(thickness 1.294)
		(legacy_teardrops no)
	)
	(paper "A3")
	(title_block
		(title "Kintex 410T devboard")
		(date "2024-04-03")
		(rev "1.1.2")
		(comment 9 "footprints 859-864 of 975")
	)
	(layers
		(0 "F.Cu" mixed)
		(4 "In1.Cu" power)
		(6 "In2.Cu" power)
		(8 "In3.Cu" mixed)
		(10 "In4.Cu" power)
		(12 "In5.Cu" mixed)
		(14 "In6.Cu" power)
		(16 "In7.Cu" mixed)
		(18 "In8.Cu" power)
		(2 "B.Cu" mixed)
		(9 "F.Adhes" user "F.Adhesive")
		(11 "B.Adhes" user "B.Adhesive")
		(13 "F.Paste" user)
		(15 "B.Paste" user)
		(5 "F.SilkS" user "F.Silkscreen")
		(7 "B.SilkS" user "B.Silkscreen")
		(1 "F.Mask" user)
		(3 "B.Mask" user)
		(17 "Dwgs.User" user "User.Drawings")
		(19 "Cmts.User" user "User.Comments")
		(21 "Eco1.User" user "User.Eco1")
		(23 "Eco2.User" user "User.Eco2")
		(25 "Edge.Cuts" user)
		(27 "Margin" user)
		(31 "F.CrtYd" user "F.Courtyard")
		(29 "B.CrtYd" user "B.Courtyard")
		(35 "F.Fab" user)
		(33 "B.Fab" user)
	)
	(footprint "antmicro-footprints:C_0402_1005Metric"
		(layer "B.Cu")
		(at 223.625 130.65)
		(descr "Capacitor SMD 0402")
		(tags "capacitor SMD 0402")
		(property "Reference" "C176"
			(at 1.375 -0.45 180)
			(layer "B.SilkS")
			(effects
				(font
					(size 0.7 0.7)
					(thickness 0.15)
				)
				(justify left bottom mirror)
			)
		)
		(property "Value" "C_100n_0402"
			(at 0 -1.169 180)
			(layer "B.Fab")
			(effects
				(font
					(size 0.7 0.7)
					(thickness 0.15)
				)
				(justify left bottom mirror)
			)
		)
		(property "Description" "SMD Multilayer Ceramic Capacitor, 0.1 µF, 50 V, 0402 [1005 Metric], ± 10%, X5R, GRM Series"
			(at 0 0 0)
			(layer "F.Fab")
			(hide yes)
			(effects
				(font
					(size 1.27 1.27)
					(thickness 0.15)
				)
			)
		)
		(property "Author" "Antmicro"
			(at 0 0 0)
			(layer "B.Fab")
			(hide yes)
			(effects
				(font
					(size 1 1)
					(thickness 0.15)
				)
				(justify mirror)
			)
		)
		(property "Dielectric" "X5R"
			(at 0 0 0)
			(layer "B.Fab")
			(hide yes)
			(effects
				(font
					(size 1 1)
					(thickness 0.15)
				)
				(justify mirror)
			)
		)
		(property "License" "Apache-2.0"
			(at 0 0 0)
			(layer "B.Fab")
			(hide yes)
			(effects
				(font
					(size 1 1)
					(thickness 0.15)
				)
				(justify mirror)
			)
		)
		(property "MPN" "GRM155R61H104KE14D"
			(at 0 0 0)
			(layer "B.Fab")
			(hide yes)
			(effects
				(font
					(size 1 1)
					(thickness 0.15)
				)
				(justify mirror)
			)
		)
		(property "Manufacturer" "Murata"
			(at 0 0 0)
			(layer "B.Fab")
			(hide yes)
			(effects
				(font
					(size 1 1)
					(thickness 0.15)
				)
				(justify mirror)
			)
		)
		(property "Val" "100n"
			(at 0 0 0)
			(layer "B.Fab")
			(hide yes)
			(effects
				(font
					(size 1 1)
					(thickness 0.15)
				)
				(justify mirror)
			)
		)
		(property "Voltage" "50V"
			(at 0 0 0)
			(layer "B.Fab")
			(hide yes)
			(effects
				(font
					(size 1 1)
					(thickness 0.15)
				)
				(justify mirror)
			)
		)
		(sheetname "DRAM + SRAM")
		(sheetfile "ram.kicad_sch")
		(attr smd)
		(fp_rect
			(start -0.925 0.47)
			(end 0.925 -0.47)
			(stroke
				(width 0.05)
				(type default)
			)
			(fill no)
			(layer "B.CrtYd")
		)
		(fp_line
			(start -0.494 -0.248)
			(end -0.494 0.25)
			(stroke
				(width 0.15)
				(type solid)
			)
			(layer "B.Fab")
		)
		(fp_line
			(start -0.494 0.25)
			(end 0.504 0.25)
			(stroke
				(width 0.15)
				(type solid)
			)
			(layer "B.Fab")
		)
		(fp_line
			(start 0.504 -0.248)
			(end -0.494 -0.248)
			(stroke
				(width 0.15)
				(type solid)
			)
			(layer "B.Fab")
		)
		(fp_line
			(start 0.504 0.25)
			(end 0.504 -0.248)
			(stroke
				(width 0.15)
				(type solid)
			)
			(layer "B.Fab")
		)
		(pad "1" smd roundrect
			(at -0.48 0)
			(size 0.59 0.64)
			(layers "B.Cu" "B.Mask" "B.Paste")
			(roundrect_rratio 0.25)
			(net 1 "GND")
			(pintype "passive")
		)
		(pad "2" smd roundrect
			(at 0.48 0)
			(size 0.59 0.64)
			(layers "B.Cu" "B.Mask" "B.Paste")
			(roundrect_rratio 0.25)
			(net 24 "+3V3")
			(pintype "passive")
		)
	)
	(footprint "antmicro-footprints:R_0402_1005Metric"
		(layer "B.Cu")
		(at 197.991252 99.25 90)
		(descr "Resistor SMD 0402")
		(tags "resistor SMD 0402")
		(property "Reference" "R240"
			(at -3.8 0.408748 270)
			(layer "B.SilkS")
			(effects
				(font
					(size 0.7 0.7)
					(thickness 0.15)
				)
				(justify left bottom mirror)
			)
		)
		(property "Value" "R_1k_0402"
			(at 0 -1.4 270)
			(layer "B.Fab")
			(effects
				(font
					(size 0.7 0.7)
					(thickness 0.15)
				)
				(justify left bottom mirror)
			)
		)
		(property "Description" "SMD Chip Resistor, 1 kohm, ± 1%, 63 mW, 0402 [1005 Metric], Thick Film, General Purpose"
			(at 0 0 90)
			(layer "F.Fab")
			(hide yes)
			(effects
				(font
					(size 1.27 1.27)
					(thickness 0.15)
				)
			)
		)
		(property "Author" "Antmicro"
			(at 297.241252 -98.741252 0)
			(layer "B.Fab")
			(hide yes)
			(effects
				(font
					(size 1 1)
					(thickness 0.15)
				)
				(justify mirror)
			)
		)
		(property "License" "Apache-2.0"
			(at 297.241252 -98.741252 0)
			(layer "B.Fab")
			(hide yes)
			(effects
				(font
					(size 1 1)
					(thickness 0.15)
				)
				(justify mirror)
			)
		)
		(property "MPN" "CR0402-FX-1001GLF"
			(at 297.241252 -98.741252 0)
			(layer "B.Fab")
			(hide yes)
			(effects
				(font
					(size 1 1)
					(thickness 0.15)
				)
				(justify mirror)
			)
		)
		(property "Manufacturer" "Bourns"
			(at 297.241252 -98.741252 0)
			(layer "B.Fab")
			(hide yes)
			(effects
				(font
					(size 1 1)
					(thickness 0.15)
				)
				(justify mirror)
			)
		)
		(property "Tolerance" "1%"
			(at 297.241252 -98.741252 0)
			(layer "B.Fab")
			(hide yes)
			(effects
				(font
					(size 1 1)
					(thickness 0.15)
				)
				(justify mirror)
			)
		)
		(property "Val" "1k"
			(at 297.241252 -98.741252 0)
			(layer "B.Fab")
			(hide yes)
			(effects
				(font
					(size 1 1)
					(thickness 0.15)
				)
				(justify mirror)
			)
		)
		(sheetname "HDMI + Ethernet")
		(sheetfile "hdmi-ethernet.kicad_sch")
		(attr smd)
		(fp_rect
			(start -0.925 0.47)
			(end 0.925 -0.47)
			(stroke
				(width 0.05)
				(type default)
			)
			(fill no)
			(layer "B.CrtYd")
		)
		(fp_rect
			(start -0.5 0.25)
			(end 0.5 -0.25)
			(stroke
				(width 0.15)
				(type solid)
			)
			(fill no)
			(layer "B.Fab")
		)
		(pad "1" smd roundrect
			(at -0.48 0 90)
			(size 0.59 0.64)
			(layers "B.Cu" "B.Mask" "B.Paste")
			(roundrect_rratio 0.25)
			(net 24 "+3V3")
			(pintype "passive")
		)
		(pad "2" smd roundrect
			(at 0.48 0 90)
			(size 0.59 0.64)
			(layers "B.Cu" "B.Mask" "B.Paste")
			(roundrect_rratio 0.25)
			(net 523 "/FPGA Bank 16 & 17/GBE_RGMII.MDIO")
			(pintype "passive")
		)
	)
	(footprint "antmicro-footprints:C_0603_1608Metric"
		(layer "B.Cu")
		(at 161.8 144.4 -90)
		(descr "Capacitor SMD 0603")
		(tags "capacitor 0603")
		(property "Reference" "C167"
			(at -3.95 -0.375 90)
			(layer "B.SilkS")
			(effects
				(font
					(size 0.7 0.7)
					(thickness 0.15)
				)
				(justify left bottom mirror)
			)
		)
		(property "Value" "C_47u_0603"
			(at 0 -1.6 90)
			(layer "B.Fab")
			(effects
				(font
					(size 0.7 0.7)
					(thickness 0.15)
				)
				(justify left bottom mirror)
			)
		)
		(property "Description" "SMD Multilayer Ceramic Capacitor, 47 µF, 6.3 V, 0603 [1608 Metric], ± 20%, X5R, GRM Series"
			(at 0 0 270)
			(layer "F.Fab")
			(hide yes)
			(effects
				(font
					(size 1.27 1.27)
					(thickness 0.15)
				)
			)
		)
		(property "Author" "Antmicro"
			(at 17.4 306.2 0)
			(layer "B.Fab")
			(hide yes)
			(effects
				(font
					(size 1 1)
					(thickness 0.15)
				)
				(justify mirror)
			)
		)
		(property "Dielectric" ""
			(at 17.4 306.2 0)
			(layer "B.Fab")
			(hide yes)
			(effects
				(font
					(size 1 1)
					(thickness 0.15)
				)
				(justify mirror)
			)
		)
		(property "License" "Apache-2.0"
			(at 17.4 306.2 0)
			(layer "B.Fab")
			(hide yes)
			(effects
				(font
					(size 1 1)
					(thickness 0.15)
				)
				(justify mirror)
			)
		)
		(property "MPN" "GRM188R60J476ME15D"
			(at 17.4 306.2 0)
			(layer "B.Fab")
			(hide yes)
			(effects
				(font
					(size 1 1)
					(thickness 0.15)
				)
				(justify mirror)
			)
		)
		(property "Manufacturer" "Murata"
			(at 17.4 306.2 0)
			(layer "B.Fab")
			(hide yes)
			(effects
				(font
					(size 1 1)
					(thickness 0.15)
				)
				(justify mirror)
			)
		)
		(property "Val" "47u"
			(at 17.4 306.2 0)
			(layer "B.Fab")
			(hide yes)
			(effects
				(font
					(size 1 1)
					(thickness 0.15)
				)
				(justify mirror)
			)
		)
		(property "Voltage" ""
			(at 17.4 306.2 0)
			(layer "B.Fab")
			(hide yes)
			(effects
				(font
					(size 1 1)
					(thickness 0.15)
				)
				(justify mirror)
			)
		)
		(sheetname "DRAM + SRAM")
		(sheetfile "ram.kicad_sch")
		(attr smd)
		(fp_line
			(start -0.15 0.4)
			(end 0.15 0.4)
			(stroke
				(width 0.15)
				(type solid)
			)
			(layer "B.SilkS")
		)
		(fp_line
			(start -0.15 -0.4)
			(end 0.15 -0.4)
			(stroke
				(width 0.15)
				(type solid)
			)
			(layer "B.SilkS")
		)
		(fp_rect
			(start -1.25 0.65)
			(end 1.25 -0.65)
			(stroke
				(width 0.05)
				(type solid)
			)
			(fill no)
			(layer "B.CrtYd")
		)
		(fp_rect
			(start -0.8 0.4)
			(end 0.8 -0.4)
			(stroke
				(width 0.15)
				(type solid)
			)
			(fill no)
			(layer "B.Fab")
		)
		(pad "1" smd roundrect
			(at -0.7 0 270)
			(size 0.8 1)
			(layers "B.Cu" "B.Mask" "B.Paste")
			(roundrect_rratio 0.2)
			(net 1 "GND")
			(pintype "passive")
		)
		(pad "2" smd roundrect
			(at 0.7 0 270)
			(size 0.8 1)
			(layers "B.Cu" "B.Mask" "B.Paste")
			(roundrect_rratio 0.2)
			(net 7 "+0V675_VTT")
			(pintype "passive")
		)
	)
	(footprint "antmicro-footprints:C_0402_1005Metric"
		(layer "B.Cu")
		(at 208 124.5 180)
		(descr "Capacitor SMD 0402")
		(tags "capacitor SMD 0402")
		(property "Reference" "C20"
			(at -1.075 0.45 0)
			(layer "B.SilkS")
			(effects
				(font
					(size 0.7 0.7)
					(thickness 0.15)
				)
				(justify left bottom mirror)
			)
		)
		(property "Value" "C_100n_0402"
			(at 0 -1.169 0)
			(layer "B.Fab")
			(effects
				(font
					(size 0.7 0.7)
					(thickness 0.15)
				)
				(justify left bottom mirror)
			)
		)
		(property "Description" "SMD Multilayer Ceramic Capacitor, 0.1 µF, 50 V, 0402 [1005 Metric], ± 10%, X5R, GRM Series"
			(at 0 0 180)
			(layer "F.Fab")
			(hide yes)
			(effects
				(font
					(size 1.27 1.27)
					(thickness 0.15)
				)
			)
		)
		(property "Author" "Antmicro"
			(at 416 249 0)
			(layer "B.Fab")
			(hide yes)
			(effects
				(font
					(size 1 1)
					(thickness 0.15)
				)
				(justify mirror)
			)
		)
		(property "Dielectric" "X5R"
			(at 416 249 0)
			(layer "B.Fab")
			(hide yes)
			(effects
				(font
					(size 1 1)
					(thickness 0.15)
				)
				(justify mirror)
			)
		)
		(property "License" "Apache-2.0"
			(at 416 249 0)
			(layer "B.Fab")
			(hide yes)
			(effects
				(font
					(size 1 1)
					(thickness 0.15)
				)
				(justify mirror)
			)
		)
		(property "MPN" "GRM155R61H104KE14D"
			(at 416 249 0)
			(layer "B.Fab")
			(hide yes)
			(effects
				(font
					(size 1 1)
					(thickness 0.15)
				)
				(justify mirror)
			)
		)
		(property "Manufacturer" "Murata"
			(at 416 249 0)
			(layer "B.Fab")
			(hide yes)
			(effects
				(font
					(size 1 1)
					(thickness 0.15)
				)
				(justify mirror)
			)
		)
		(property "Val" "100n"
			(at 416 249 0)
			(layer "B.Fab")
			(hide yes)
			(effects
				(font
					(size 1 1)
					(thickness 0.15)
				)
				(justify mirror)
			)
		)
		(property "Voltage" "50V"
			(at 416 249 0)
			(layer "B.Fab")
			(hide yes)
			(effects
				(font
					(size 1 1)
					(thickness 0.15)
				)
				(justify mirror)
			)
		)
		(sheetname "FPGA Bank 14 & 15")
		(sheetfile "fpga-bank-14-15.kicad_sch")
		(attr smd)
		(fp_rect
			(start -0.925 0.47)
			(end 0.925 -0.47)
			(stroke
				(width 0.05)
				(type default)
			)
			(fill no)
			(layer "B.CrtYd")
		)
		(fp_line
			(start 0.504 0.25)
			(end 0.504 -0.248)
			(stroke
				(width 0.15)
				(type solid)
			)
			(layer "B.Fab")
		)
		(fp_line
			(start 0.504 -0.248)
			(end -0.494 -0.248)
			(stroke
				(width 0.15)
				(type solid)
			)
			(layer "B.Fab")
		)
		(fp_line
			(start -0.494 0.25)
			(end 0.504 0.25)
			(stroke
				(width 0.15)
				(type solid)
			)
			(layer "B.Fab")
		)
		(fp_line
			(start -0.494 -0.248)
			(end -0.494 0.25)
			(stroke
				(width 0.15)
				(type solid)
			)
			(layer "B.Fab")
		)
		(pad "1" smd roundrect
			(at -0.48 0 180)
			(size 0.59 0.64)
			(layers "B.Cu" "B.Mask" "B.Paste")
			(roundrect_rratio 0.25)
			(net 1 "GND")
			(pintype "passive")
		)
		(pad "2" smd roundrect
			(at 0.48 0 180)
			(size 0.59 0.64)
			(layers "B.Cu" "B.Mask" "B.Paste")
			(roundrect_rratio 0.25)
			(net 2 "VCC_USR_A")
			(pintype "passive")
		)
	)
	(footprint "antmicro-footprints:C_0603_1608Metric"
		(layer "B.Cu")
		(at 216.1 123.6 90)
		(descr "Capacitor SMD 0603")
		(tags "capacitor 0603")
		(property "Reference" "C6"
			(at -0.8 1.4 90)
			(layer "B.SilkS")
			(effects
				(font
					(size 0.7 0.7)
					(thickness 0.15)
				)
				(justify right bottom mirror)
			)
		)
		(property "Value" "C_47u_0603"
			(at 0 -1.6 90)
			(layer "B.Fab")
			(effects
				(font
					(size 0.7 0.7)
					(thickness 0.15)
				)
				(justify right bottom mirror)
			)
		)
		(property "Description" "SMD Multilayer Ceramic Capacitor, 47 µF, 6.3 V, 0603 [1608 Metric], ± 20%, X5R, GRM Series"
			(at 0 0 90)
			(layer "F.Fab")
			(hide yes)
			(effects
				(font
					(size 1.27 1.27)
					(thickness 0.15)
				)
			)
		)
		(property "Author" "Antmicro"
			(at 339.7 -92.5 0)
			(layer "B.Fab")
			(hide yes)
			(effects
				(font
					(size 1 1)
					(thickness 0.15)
				)
				(justify mirror)
			)
		)
		(property "Dielectric" ""
			(at 339.7 -92.5 0)
			(layer "B.Fab")
			(hide yes)
			(effects
				(font
					(size 1 1)
					(thickness 0.15)
				)
				(justify mirror)
			)
		)
		(property "License" "Apache-2.0"
			(at 339.7 -92.5 0)
			(layer "B.Fab")
			(hide yes)
			(effects
				(font
					(size 1 1)
					(thickness 0.15)
				)
				(justify mirror)
			)
		)
		(property "MPN" "GRM188R60J476ME15D"
			(at 339.7 -92.5 0)
			(layer "B.Fab")
			(hide yes)
			(effects
				(font
					(size 1 1)
					(thickness 0.15)
				)
				(justify mirror)
			)
		)
		(property "Manufacturer" "Murata"
			(at 339.7 -92.5 0)
			(layer "B.Fab")
			(hide yes)
			(effects
				(font
					(size 1 1)
					(thickness 0.15)
				)
				(justify mirror)
			)
		)
		(property "Val" "47u"
			(at 339.7 -92.5 0)
			(layer "B.Fab")
			(hide yes)
			(effects
				(font
					(size 1 1)
					(thickness 0.15)
				)
				(justify mirror)
			)
		)
		(property "Voltage" ""
			(at 339.7 -92.5 0)
			(layer "B.Fab")
			(hide yes)
			(effects
				(font
					(size 1 1)
					(thickness 0.15)
				)
				(justify mirror)
			)
		)
		(sheetname "FPGA Bank 14 & 15")
		(sheetfile "fpga-bank-14-15.kicad_sch")
		(attr smd)
		(fp_line
			(start -0.15 -0.4)
			(end 0.15 -0.4)
			(stroke
				(width 0.15)
				(type solid)
			)
			(layer "B.SilkS")
		)
		(fp_line
			(start -0.15 0.4)
			(end 0.15 0.4)
			(stroke
				(width 0.15)
				(type solid)
			)
			(layer "B.SilkS")
		)
		(fp_rect
			(start -1.25 0.65)
			(end 1.25 -0.65)
			(stroke
				(width 0.05)
				(type solid)
			)
			(fill no)
			(layer "B.CrtYd")
		)
		(fp_rect
			(start -0.8 0.4)
			(end 0.8 -0.4)
			(stroke
				(width 0.15)
				(type solid)
			)
			(fill no)
			(layer "B.Fab")
		)
		(pad "1" smd roundrect
			(at -0.7 0 90)
			(size 0.8 1)
			(layers "B.Cu" "B.Mask" "B.Paste")
			(roundrect_rratio 0.2)
			(net 1 "GND")
			(pintype "passive")
		)
		(pad "2" smd roundrect
			(at 0.7 0 90)
			(size 0.8 1)
			(layers "B.Cu" "B.Mask" "B.Paste")
			(roundrect_rratio 0.2)
			(net 2 "VCC_USR_A")
			(pintype "passive")
		)
	)
	(footprint "antmicro-footprints:C_0201"
		(layer "B.Cu")
		(at 192.3 120.2 -45)
		(descr "Capacitor SMD 0201")
		(tags "capacitor SMD 0201")
		(property "Reference" "C115"
			(at -4.348707 -36.027091 315)
			(unlocked yes)
			(layer "B.SilkS")
			(effects
				(font
					(size 0.7 0.7)
					(thickness 0.15)
				)
				(justify left bottom mirror)
			)
		)
		(property "Value" "C_100n_0201"
			(at 0 -1.399999 135)
			(layer "B.Fab")
			(effects
				(font
					(size 0.7 0.7)
					(thickness 0.15)
				)
				(justify left bottom mirror)
			)
		)
		(property "Description" "SMD Multilayer Ceramic Capacitor, 0.1 µF, 6.3 V, 0201 [0603 Metric], ± 10%, X6S, CC Series"
			(at 0 0 315)
			(layer "F.Fab")
			(hide yes)
			(effects
				(font
					(size 1.27 1.27)
					(thickness 0.15)
				)
			)
		)
		(property "Author" "Antmicro"
			(at -28.670869 171.182399 0)
			(layer "B.Fab")
			(hide yes)
			(effects
				(font
					(size 1 1)
					(thickness 0.15)
				)
				(justify mirror)
			)
		)
		(property "Dielectric" ""
			(at -28.670869 171.182399 0)
			(layer "B.Fab")
			(hide yes)
			(effects
				(font
					(size 1 1)
					(thickness 0.15)
				)
				(justify mirror)
			)
		)
		(property "License" "Apache-2.0"
			(at -28.670869 171.182399 0)
			(layer "B.Fab")
			(hide yes)
			(effects
				(font
					(size 1 1)
					(thickness 0.15)
				)
				(justify mirror)
			)
		)
		(property "MPN" "CC0201KRX6S5BB104"
			(at -28.670869 171.182399 0)
			(layer "B.Fab")
			(hide yes)
			(effects
				(font
					(size 1 1)
					(thickness 0.15)
				)
				(justify mirror)
			)
		)
		(property "Manufacturer" "YAGEO"
			(at -28.670869 171.182399 0)
			(layer "B.Fab")
			(hide yes)
			(effects
				(font
					(size 1 1)
					(thickness 0.15)
				)
				(justify mirror)
			)
		)
		(property "Val" "100n"
			(at -28.670869 171.182399 0)
			(layer "B.Fab")
			(hide yes)
			(effects
				(font
					(size 1 1)
					(thickness 0.15)
				)
				(justify mirror)
			)
		)
		(property "Voltage" ""
			(at -28.670869 171.182399 0)
			(layer "B.Fab")
			(hide yes)
			(effects
				(font
					(size 1 1)
					(thickness 0.15)
				)
				(justify mirror)
			)
		)
		(sheetname "FPGA supply")
		(sheetfile "fpga-supply.kicad_sch")
		(attr smd)
		(fp_poly
			(pts
				(xy -0.7 0.35) (xy 0.7 0.35) (xy 0.7 -0.35) (xy -0.7 -0.35)
			)
			(stroke
				(width 0.05)
				(type default)
			)
			(fill no)
			(layer "B.CrtYd")
		)
		(fp_poly
			(pts
				(xy 0.3 -0.15) (xy -0.301 -0.15) (xy -0.301 0.149) (xy 0.3 0.149)
			)
			(stroke
				(width 0.15)
				(type solid)
			)
			(fill no)
			(layer "B.Fab")
		)
		(pad "" smd roundrect
			(at -0.349 0.002 315)
			(size 0.318 0.36)
			(layers "B.Paste")
			(roundrect_rratio 0.25)
		)
		(pad "" smd roundrect
			(at 0.341 0.002 315)
			(size 0.318 0.36)
			(layers "B.Paste")
			(roundrect_rratio 0.25)
		)
		(pad "1" smd roundrect
			(at -0.321 0.002 315)
			(size 0.46 0.4)
			(layers "B.Cu" "B.Mask")
			(roundrect_rratio 0.25)
			(net 6 "+1V0_MGTAVCC")
			(pintype "passive")
		)
		(pad "2" smd roundrect
			(at 0.32 0.002 315)
			(size 0.46 0.4)
			(layers "B.Cu" "B.Mask")
			(roundrect_rratio 0.25)
			(net 1 "GND")
			(pintype "passive")
		)
	)
)
